(kicad_pcb
	(version 20211014)
	(generator pcbnew)
	(general
    (thickness 1.6)
  )
	(paper "A4")
	(title_block
    (title "SA800U (Snapdragon 845) Baseboard")
    (date "2023-10-19")
    (rev "1.0.3")
    (company "Antmicro Ltd.")
    (comment 1 "www.antmicro.com")
		(comment 9 "footprints 33-37 of 589")
	)
	(layers
    (0 "F.Cu" signal)
    (1 "In1.Cu" power)
    (2 "In2.Cu" signal)
    (3 "In3.Cu" signal)
    (4 "In4.Cu" power)
    (31 "B.Cu" signal)
    (32 "B.Adhes" user "B.Adhesive")
    (33 "F.Adhes" user "F.Adhesive")
    (34 "B.Paste" user)
    (35 "F.Paste" user)
    (36 "B.SilkS" user "B.Silkscreen")
    (37 "F.SilkS" user "F.Silkscreen")
    (38 "B.Mask" user)
    (39 "F.Mask" user)
    (40 "Dwgs.User" user "User.Drawings")
    (41 "Cmts.User" user "User.Comments")
    (42 "Eco1.User" user "User.Eco1")
    (43 "Eco2.User" user "User.Eco2")
    (44 "Edge.Cuts" user)
    (45 "Margin" user)
    (46 "B.CrtYd" user "B.Courtyard")
    (47 "F.CrtYd" user "F.Courtyard")
    (48 "B.Fab" user)
    (49 "F.Fab" user)
  )
	(footprint "sa800u-baseboard-hw-footprints:QFN-24-1EP_4x4mm_EP2.1x2.1mm" (layer "F.Cu")
    (tedit 5DC5F6A3)
    (at 87.05 136.275 180)
    (descr "QFN, 24 Pin")
    (tags "QFN NoLead")
    (property "Author" "Antmicro")
    (property "License" "Apache-2.0")
    (property "MPN" "STUSB4500QTR")
    (property "Manufacturer" "STMicroelectronics")
    (property "Sheetfile" "usb-pd.kicad_sch")
    (property "Sheetname" "USB-PD")
    (attr smd)
    (fp_text reference "U23" (at -2.31 -0.415 180) (layer "F.SilkS")
      (effects (font (size 0.7 0.7) (thickness 0.15)) (justify left bottom))
    )
    (fp_text value "STUSB4500_QFN" (at 0 3.4 180) (layer "F.Fab")
      (effects (font (size 0.7 0.7) (thickness 0.15)) (justify left bottom))
    )
    (fp_text user "${REFERENCE}" (at -2.503 5.4 180) (layer "F.Fab") hide
      (effects (font (size 0.7 0.7) (thickness 0.15)) (justify left bottom))
    )
    (fp_text user "Author: Antmicro" (at -2.503 7.8 180) (layer "F.Fab") hide
      (effects (font (size 0.7 0.7) (thickness 0.15)) (justify left bottom))
    )
    (fp_text user "License: Apache-2.0" (at -2.503 6.6 180) (layer "F.Fab") hide
      (effects (font (size 0.7 0.7) (thickness 0.15)) (justify left bottom))
    )
    (fp_line (start -2.11 -1.636) (end -2.11 -2.11) (layer "F.SilkS") (width 0.15))
    (fp_line (start -1.635 2.108) (end -2.11 2.108) (layer "F.SilkS") (width 0.15))
    (fp_line (start 2.108 2.108) (end 2.108 1.634) (layer "F.SilkS") (width 0.15))
    (fp_line (start 2.108 -2.11) (end 2.108 -1.635) (layer "F.SilkS") (width 0.15))
    (fp_line (start -2.11 2.108) (end -2.11 1.634) (layer "F.SilkS") (width 0.15))
    (fp_line (start 1.634 2.108) (end 2.108 2.108) (layer "F.SilkS") (width 0.15))
    (fp_line (start -1.635 -2.11) (end -2.11 -2.11) (layer "F.SilkS") (width 0.15))
    (fp_line (start 1.634 -2.11) (end 2.108 -2.11) (layer "F.SilkS") (width 0.15))
    (fp_circle (center -2.3 -2.3) (end -2.25 -2.3) (layer "F.SilkS") (width 0.15) (fill solid))
    (fp_rect (start -2.503 -2.503) (end 2.5 2.5) (layer "F.CrtYd") (width 0.05) (fill none))
    (fp_line (start 1.999 -2) (end 1.999 1.999) (layer "F.Fab") (width 0.15))
    (fp_line (start -2 -1) (end -1 -2) (layer "F.Fab") (width 0.15))
    (fp_line (start -1 -2) (end 1.999 -2) (layer "F.Fab") (width 0.15))
    (fp_line (start -2 1.999) (end -2 -1) (layer "F.Fab") (width 0.15))
    (fp_line (start 1.999 1.999) (end -2 1.999) (layer "F.Fab") (width 0.15))
    (pad "" smd roundrect (at -0.5 -0.5 180) (size 0.8 0.8) (layers "F.Paste") (roundrect_rratio 0.238095))
    (pad "" smd roundrect (at 0.5 0.5 180) (size 0.8 0.8) (layers "F.Paste") (roundrect_rratio 0.238095))
    (pad "" smd roundrect (at 0.5 -0.5 180) (size 0.8 0.8) (layers "F.Paste") (roundrect_rratio 0.238095))
    (pad "" smd roundrect (at -0.5 0.5 180) (size 0.8 0.8) (layers "F.Paste") (roundrect_rratio 0.238095))
    (pad "1" smd roundrect (at -1.938 -1.25 180) (size 0.825 0.25) (layers "F.Cu" "F.Paste" "F.Mask") (roundrect_rratio 0.25)
      (net 143 "/USB-PD/PD_CC1") (pinfunction "CC1DB") (pintype "bidirectional"))
    (pad "2" smd roundrect (at -1.938 -0.75 180) (size 0.825 0.25) (layers "F.Cu" "F.Paste" "F.Mask") (roundrect_rratio 0.25)
      (net 143 "/USB-PD/PD_CC1") (pinfunction "CC1") (pintype "bidirectional"))
    (pad "3" smd roundrect (at -1.938 -0.25 180) (size 0.825 0.25) (layers "F.Cu" "F.Paste" "F.Mask") (roundrect_rratio 0.25)
      (net 660 "unconnected-(U23-Pad3)") (pinfunction "NC") (pintype "no_connect"))
    (pad "4" smd roundrect (at -1.938 0.248 180) (size 0.825 0.25) (layers "F.Cu" "F.Paste" "F.Mask") (roundrect_rratio 0.25)
      (net 144 "/USB-PD/PD_CC2") (pinfunction "CC2") (pintype "bidirectional"))
    (pad "5" smd roundrect (at -1.938 0.748 180) (size 0.825 0.25) (layers "F.Cu" "F.Paste" "F.Mask") (roundrect_rratio 0.25)
      (net 144 "/USB-PD/PD_CC2") (pinfunction "CC2DB") (pintype "bidirectional"))
    (pad "6" smd roundrect (at -1.938 1.249 180) (size 0.825 0.25) (layers "F.Cu" "F.Paste" "F.Mask") (roundrect_rratio 0.25)
      (net 351 "USB_PD_DISABLE") (pinfunction "RESET") (pintype "input"))
    (pad "7" smd roundrect (at -1.25 1.937 180) (size 0.25 0.825) (layers "F.Cu" "F.Paste" "F.Mask") (roundrect_rratio 0.25)
      (net 150 "I2C10_SCL") (pinfunction "SCL") (pintype "input"))
    (pad "8" smd roundrect (at -0.75 1.937 180) (size 0.25 0.825) (layers "F.Cu" "F.Paste" "F.Mask") (roundrect_rratio 0.25)
      (net 151 "I2C10_SDA") (pinfunction "SDA") (pintype "bidirectional"))
    (pad "9" smd roundrect (at -0.25 1.937 180) (size 0.25 0.825) (layers "F.Cu" "F.Paste" "F.Mask") (roundrect_rratio 0.25)
      (net 468 "/USB-PD/DISCH") (pinfunction "DISCH") (pintype "bidirectional"))
    (pad "10" smd roundrect (at 0.248 1.937 180) (size 0.25 0.825) (layers "F.Cu" "F.Paste" "F.Mask") (roundrect_rratio 0.25)
      (net 1 "GND") (pinfunction "GND") (pintype "power_in"))
    (pad "11" smd roundrect (at 0.748 1.937 180) (size 0.25 0.825) (layers "F.Cu" "F.Paste" "F.Mask") (roundrect_rratio 0.25)
      (net 335 "/USB-PD/ATTACH") (pinfunction "ATTACH") (pintype "output"))
    (pad "12" smd roundrect (at 1.249 1.937 180) (size 0.25 0.825) (layers "F.Cu" "F.Paste" "F.Mask") (roundrect_rratio 0.25)
      (net 160 "Net-(R154-Pad2)") (pinfunction "ADDR0") (pintype "input"))
    (pad "13" smd roundrect (at 1.937 1.249 180) (size 0.825 0.25) (layers "F.Cu" "F.Paste" "F.Mask") (roundrect_rratio 0.25)
      (net 411 "Net-(R155-Pad2)") (pinfunction "ADDR1") (pintype "input"))
    (pad "14" smd roundrect (at 1.937 0.748 180) (size 0.825 0.25) (layers "F.Cu" "F.Paste" "F.Mask") (roundrect_rratio 0.25)
      (net 170 "/USB-PD/STUSB4500_PWR_OK3") (pinfunction "POWER_OK3") (pintype "output"))
    (pad "15" smd roundrect (at 1.937 0.248 180) (size 0.825 0.25) (layers "F.Cu" "F.Paste" "F.Mask") (roundrect_rratio 0.25)
      (net 334 "/USB-PD/GPIO") (pinfunction "GPIO") (pintype "output"))
    (pad "16" smd roundrect (at 1.937 -0.25 180) (size 0.825 0.25) (layers "F.Cu" "F.Paste" "F.Mask") (roundrect_rratio 0.25)
      (net 467 "/USB-PD/EN_SINK") (pinfunction "VBUS_EN_SNK") (pintype "output"))
    (pad "17" smd roundrect (at 1.937 -0.75 180) (size 0.825 0.25) (layers "F.Cu" "F.Paste" "F.Mask") (roundrect_rratio 0.25)
      (net 333 "/USB-PD/AB_SIDE") (pinfunction "A_B_SIDE") (pintype "output"))
    (pad "18" smd roundrect (at 1.937 -1.25 180) (size 0.825 0.25) (layers "F.Cu" "F.Paste" "F.Mask") (roundrect_rratio 0.25)
      (net 466 "/USB-PD/VS_DISCH") (pinfunction "VBUS_VS_DISCH") (pintype "input"))
    (pad "19" smd roundrect (at 1.249 -1.938 180) (size 0.25 0.825) (layers "F.Cu" "F.Paste" "F.Mask") (roundrect_rratio 0.25)
      (net 332 "/USB-PD/ALERT") (pinfunction "~{ALERT}") (pintype "output"))
    (pad "20" smd roundrect (at 0.748 -1.938 180) (size 0.25 0.825) (layers "F.Cu" "F.Paste" "F.Mask") (roundrect_rratio 0.25)
      (net 169 "/USB-PD/STUSB4500_PWR_OK2") (pinfunction "POWER_OK2") (pintype "output"))
    (pad "21" smd roundrect (at 0.248 -1.938 180) (size 0.25 0.825) (layers "F.Cu" "F.Paste" "F.Mask") (roundrect_rratio 0.25)
      (net 140 "/USB-PD/VREG_1V2") (pinfunction "VREG_1V2") (pintype "output"))
    (pad "22" smd roundrect (at -0.25 -1.938 180) (size 0.25 0.825) (layers "F.Cu" "F.Paste" "F.Mask") (roundrect_rratio 0.25)
      (net 1 "GND") (pinfunction "VSYS") (pintype "power_in"))
    (pad "23" smd roundrect (at -0.75 -1.938 180) (size 0.25 0.825) (layers "F.Cu" "F.Paste" "F.Mask") (roundrect_rratio 0.25)
      (net 141 "/USB-PD/VREG_2V7") (pinfunction "VREG_2V7") (pintype "output"))
    (pad "24" smd roundrect (at -1.25 -1.938 180) (size 0.25 0.825) (layers "F.Cu" "F.Paste" "F.Mask") (roundrect_rratio 0.25)
      (net 107 "/USB-PD/PD_VBUS") (pinfunction "VDD") (pintype "power_in"))
    (pad "25" smd rect (at 0 0 180) (size 2.1 2.1) (layers "F.Cu" "F.Mask")
      (net 1 "GND") (pinfunction "EP") (pintype "power_in"))
  )
	(footprint "sa800u-baseboard-hw-footprints:C_0402_1005Metric" (layer "F.Cu")
    (tedit 616D63CF)
    (at 119 108.8 180)
    (descr "Capacitor SMD 0402")
    (tags "capacitor SMD 0402")
    (property "Author" "Antmicro")
    (property "Dielectric" "X5R")
    (property "License" "Apache-2.0")
    (property "MPN" "GRM155R61H104KE14D")
    (property "Manufacturer" "Murata")
    (property "Sheetfile" "lcm.kicad_sch")
    (property "Sheetname" "LCM")
    (property "Val" "100n")
    (property "Voltage" "50V")
    (attr smd)
    (fp_text reference "C97" (at 3.02 -0.65 180) (layer "F.SilkS")
      (effects (font (size 0.7 0.7) (thickness 0.15)) (justify left bottom))
    )
    (fp_text value "C_100n_0402" (at 0 1.4 180) (layer "F.Fab")
      (effects (font (size 0.7 0.7) (thickness 0.15)) (justify left bottom))
    )
    (fp_text user "${REFERENCE}" (at -0.932 3.168 180) (layer "F.Fab") hide
      (effects (font (size 0.7 0.7) (thickness 0.15)) (justify left bottom))
    )
    (fp_text user "Author: Antmicro" (at -0.932 4.17 180) (layer "F.Fab") hide
      (effects (font (size 0.7 0.7) (thickness 0.15)) (justify left bottom))
    )
    (fp_text user "License: Apache-2.0" (at -0.932 5.17 180) (layer "F.Fab") hide
      (effects (font (size 0.7 0.7) (thickness 0.15)) (justify left bottom))
    )
    (fp_rect (start -0.94 -0.47) (end 0.94 0.47) (layer "F.CrtYd") (width 0.05) (fill none))
    (fp_rect (start -0.499 -0.249) (end 0.499 0.249) (layer "F.Fab") (width 0.15) (fill none))
    (pad "1" smd roundrect (at -0.484 0 180) (size 0.59 0.64) (layers "F.Cu" "F.Paste" "F.Mask") (roundrect_rratio 0.25)
      (net 139 "LVS1A_1V8") (pintype "passive"))
    (pad "2" smd roundrect (at 0.484 0 180) (size 0.59 0.64) (layers "F.Cu" "F.Paste" "F.Mask") (roundrect_rratio 0.25)
      (net 1 "GND") (pintype "passive"))
  )
	(footprint "sa800u-baseboard-hw-footprints:C_0402_1005Metric" (layer "F.Cu")
    (tedit 616D63CF)
    (at 122.8 108.8)
    (descr "Capacitor SMD 0402")
    (tags "capacitor SMD 0402")
    (property "Author" "Antmicro")
    (property "Dielectric" "X5R")
    (property "License" "Apache-2.0")
    (property "MPN" "GRM155R61H104KE14D")
    (property "Manufacturer" "Murata")
    (property "Sheetfile" "lcm.kicad_sch")
    (property "Sheetname" "LCM")
    (property "Val" "100n")
    (property "Voltage" "50V")
    (attr smd)
    (fp_text reference "C98" (at 0.791 0.39) (layer "F.SilkS")
      (effects (font (size 0.7 0.7) (thickness 0.15)) (justify left bottom))
    )
    (fp_text value "C_100n_0402" (at 0 1.4) (layer "F.Fab")
      (effects (font (size 0.7 0.7) (thickness 0.15)) (justify left bottom))
    )
    (fp_text user "Author: Antmicro" (at -0.932 4.17) (layer "F.Fab") hide
      (effects (font (size 0.7 0.7) (thickness 0.15)) (justify left bottom))
    )
    (fp_text user "${REFERENCE}" (at -0.932 3.168) (layer "F.Fab") hide
      (effects (font (size 0.7 0.7) (thickness 0.15)) (justify left bottom))
    )
    (fp_text user "License: Apache-2.0" (at -0.932 5.17) (layer "F.Fab") hide
      (effects (font (size 0.7 0.7) (thickness 0.15)) (justify left bottom))
    )
    (fp_rect (start -0.94 -0.47) (end 0.94 0.47) (layer "F.CrtYd") (width 0.05) (fill none))
    (fp_rect (start -0.499 -0.249) (end 0.499 0.249) (layer "F.Fab") (width 0.15) (fill none))
    (pad "1" smd roundrect (at -0.484 0) (size 0.59 0.64) (layers "F.Cu" "F.Paste" "F.Mask") (roundrect_rratio 0.25)
      (net 131 "3V3_SYS") (pintype "passive"))
    (pad "2" smd roundrect (at 0.484 0) (size 0.59 0.64) (layers "F.Cu" "F.Paste" "F.Mask") (roundrect_rratio 0.25)
      (net 1 "GND") (pintype "passive"))
  )
	(footprint "sa800u-baseboard-hw-footprints:D_SOD-323F" (layer "F.Cu")
    (tedit 60F16F6B)
    (at 138.8 145 -90)
    (property "Author" "Antmicro")
    (property "License" "Apache-2.0")
    (property "MPN" "1N4148WS")
    (property "Manufacturer" "ON Semiconductor")
    (property "Sheetfile" "hdmi-converter.kicad_sch")
    (property "Sheetname" "HDMI converter")
    (attr smd)
    (fp_text reference "D2" (at 0.56 -1.7 90) (layer "F.SilkS")
      (effects (font (size 0.7 0.7) (thickness 0.15)) (justify left bottom))
    )
    (fp_text value "1N4148WS" (at -1.7 1.9 -90) (layer "F.Fab")
      (effects (font (size 0.7 0.7) (thickness 0.15)) (justify left bottom))
    )
    (fp_text user "Author: Antmicro" (at -1.8 4.46 -90) (layer "F.Fab") hide
      (effects (font (size 0.7 0.7) (thickness 0.15)) (justify left bottom))
    )
    (fp_text user "${REFERENCE}" (at -1.8 3.2 -90) (layer "F.Fab") hide
      (effects (font (size 0.7 0.7) (thickness 0.15)) (justify left bottom))
    )
    (fp_text user "License: Apache-2.0" (at -1.8 5.8 -90) (layer "F.Fab") hide
      (effects (font (size 0.7 0.7) (thickness 0.15)) (justify left bottom))
    )
    (fp_line (start 0.973 0.748) (end 0.623 0.748) (layer "F.SilkS") (width 0.15))
    (fp_line (start 0.623 -0.75) (end 0.973 -0.75) (layer "F.SilkS") (width 0.15))
    (fp_line (start -0.975 -0.75) (end -0.975 -0.45) (layer "F.SilkS") (width 0.15))
    (fp_line (start -0.975 0.748) (end -0.975 0.45) (layer "F.SilkS") (width 0.15))
    (fp_line (start -0.625 -0.75) (end -0.975 -0.75) (layer "F.SilkS") (width 0.15))
    (fp_line (start 0.973 0.45) (end 0.973 0.748) (layer "F.SilkS") (width 0.15))
    (fp_line (start -0.625 0.748) (end -0.975 0.748) (layer "F.SilkS") (width 0.15))
    (fp_line (start -0.5 -0.426) (end -0.5 0.424) (layer "F.SilkS") (width 0.15))
    (fp_line (start 0.973 -0.75) (end 0.973 -0.45) (layer "F.SilkS") (width 0.15))
    (fp_rect (start -1.6 -0.827) (end 1.599 0.825) (layer "F.CrtYd") (width 0.05) (fill none))
    (fp_line (start -0.85 0.623) (end -0.85 -0.625) (layer "F.Fab") (width 0.15))
    (fp_line (start -0.85 0.623) (end 0.848 0.623) (layer "F.Fab") (width 0.15))
    (fp_line (start 0.848 -0.625) (end 0.848 0.623) (layer "F.Fab") (width 0.15))
    (fp_line (start -0.85 -0.625) (end 0.848 -0.625) (layer "F.Fab") (width 0.15))
    (pad "A" smd roundrect (at 1.05 0 270) (size 0.8 0.6) (layers "F.Cu" "F.Paste" "F.Mask") (roundrect_rratio 0.15)
      (net 244 "/HDMI converter/5V_HDMI_FB_D") (pinfunction "A") (pintype "passive"))
    (pad "K" smd roundrect (at -1.051 0 270) (size 0.8 0.6) (layers "F.Cu" "F.Paste" "F.Mask") (roundrect_rratio 0.15)
      (net 245 "/HDMI converter/5V_HDMI") (pinfunction "K") (pintype "passive"))
  )
	(footprint "sa800u-baseboard-hw-footprints:LED_0603_1608Metric_G" (layer "F.Cu")
    (tedit 60C2DD7B)
    (at 81.25 150.2 -90)
    (descr "LED SMD 0603 Green")
    (tags "LED SMD 0603 Green")
    (property "Author" "Antmicro")
    (property "License" "Apache-2.0")
    (property "MPN" "KP-1608ZGC")
    (property "Manufacturer" "Kingbright")
    (property "Sheetfile" "psu.kicad_sch")
    (property "Sheetname" "PSU")
    (attr smd)
    (fp_text reference "D24" (at 0.95 -1.46 -90) (layer "F.SilkS")
      (effects (font (size 0.7 0.7) (thickness 0.15)) (justify left bottom))
    )
    (fp_text value "KP-1608EC" (at 0 1.6 -90) (layer "F.Fab")
      (effects (font (size 0.7 0.7) (thickness 0.15)) (justify left bottom))
    )
    (fp_text user "Author: Antmicro" (at -1.31 4.769 -90) (layer "F.Fab") hide
      (effects (font (size 0.7 0.7) (thickness 0.15)) (justify left bottom))
    )
    (fp_text user "${REFERENCE}" (at -1.31 3.769 -90) (layer "F.Fab") hide
      (effects (font (size 0.7 0.7) (thickness 0.15)) (justify left bottom))
    )
    (fp_text user "License: Apache-2.0" (at -1.31 5.769 -90) (layer "F.Fab") hide
      (effects (font (size 0.7 0.7) (thickness 0.15)) (justify left bottom))
    )
    (fp_line (start -0.27 -0.35) (end 0.27 -0.35) (layer "F.SilkS") (width 0.15))
    (fp_line (start -0.106328 -0.200008) (end 0.093672 -0.000008) (layer "F.SilkS") (width 0.1))
    (fp_line (start 0.093672 -0.000008) (end 0.293672 -0.000008) (layer "F.SilkS") (width 0.1))
    (fp_line (start -0.106328 -0.200008) (end -0.106328 0.199992) (layer "F.SilkS") (width 0.1))
    (fp_line (start 1.25 0.32) (end 1.25 -0.32) (layer "F.SilkS") (width 0.15))
    (fp_line (start 0.093672 -0.200008) (end 0.093672 0.199992) (layer "F.SilkS") (width 0.1))
    (fp_line (start -0.106328 -0.000008) (end -0.29 0) (layer "F.SilkS") (width 0.1))
    (fp_line (start -0.27 0.351) (end 0.27 0.351) (layer "F.SilkS") (width 0.15))
    (fp_line (start 0.093672 -0.000008) (end -0.106328 0.199992) (layer "F.SilkS") (width 0.1))
    (fp_rect (start 1.26 0.65) (end -1.26 -0.65) (layer "F.CrtYd") (width 0.05) (fill none))
    (fp_line (start -0.599 0) (end -0.201 0) (layer "F.Fab") (width 0.15))
    (fp_line (start -0.201 -0.2) (end -0.201 0) (layer "F.Fab") (width 0.15))
    (fp_line (start -0.201 0.202) (end 0.101 0) (layer "F.Fab") (width 0.15))
    (fp_line (start 0.199 -0.2) (end 0.199 -0.1) (layer "F.Fab") (width 0.15))
    (fp_line (start 0.101 0) (end -0.201 -0.2) (layer "F.Fab") (width 0.15))
    (fp_line (start -0.201 0) (end -0.201 0.202) (layer "F.Fab") (width 0.15))
    (fp_line (start 0.199 0) (end 0.597 0) (layer "F.Fab") (width 0.15))
    (fp_line (start 0.199 0.202) (end 0.199 -0.1) (layer "F.Fab") (width 0.15))
    (fp_rect (start -0.848 -0.4) (end 0.85 0.402) (layer "F.Fab") (width 0.15) (fill none))
    (pad "1" smd rect (at -0.75 0 90) (size 0.8 0.8) (layers "F.Cu" "F.Paste" "F.Mask")
      (net 152 "/PSU/AUX_VDD") (pinfunction "1") (pintype "passive"))
    (pad "2" smd rect (at 0.75 0 90) (size 0.8 0.8) (layers "F.Cu" "F.Paste" "F.Mask")
      (net 375 "Net-(D24-Pad2)") (pinfunction "2") (pintype "passive"))
  )
)
